# BASEBOARD_FAB2 (Tioga Pass) — schematic netlist excerpt (pin names and nets, part order shuffled) for the footprints in the layout excerpt that follows; sources: Cadence DE-HDL packaged netlist, KiCad conversion of Wiwynn_Tioga_Pass_MB.brd

R3P50  RES  10.0K 1% EMPTY  pkg 0402  page 196 : A = P3V3_STBY ; B = PWRGD_P3V3_STBY
R9N8  RES  4.02K 1% CHIP  pkg 0402  page 206 : A = VR_PVCCIN_CPU1_XADDR1 ; B = GND
C9P10  CAP_A  22.0UF 4V 20% X6S  pkg 0603V  page 208 : A = PVCCIN_CPU1 ; B = GND

(kicad_pcb
	(version 20260206)
	(generator "pcbnew")
	(generator_version "10.0")
	(general
		(thickness 1.6)
		(legacy_teardrops no)
	)
	(paper "A4")
	(title_block
		(title "Wiwynn_Tioga_Pass_MB.brd")
		(comment 1 "Tioga Pass / footprints 4610-4612 of 4770")
	)
	(layers
		(0 "F.Cu" signal "TOP")
		(4 "In1.Cu" signal "L2GND")
		(6 "In2.Cu" signal "L3")
		(8 "In3.Cu" signal "L4GND")
		(10 "In4.Cu" signal "L5")
		(12 "In5.Cu" signal "L6GND")
		(14 "In6.Cu" signal "L7VCC")
		(16 "In7.Cu" signal "L8VCC")
		(18 "In8.Cu" signal "L9GND")
		(20 "In9.Cu" signal "L10")
		(22 "In10.Cu" signal "L11GND")
		(24 "In11.Cu" signal "L12")
		(26 "In12.Cu" signal "L13GND")
		(2 "B.Cu" signal "BOTTOM")
		(9 "F.Adhes" user "F.Adhesive")
		(11 "B.Adhes" user "B.Adhesive")
		(13 "F.Paste" user "Package Geometry/Pastemask Top")
		(15 "B.Paste" user "Package Geometry/Pastemask Bottom")
		(5 "F.SilkS" user "Ref Des/Silkscreen Top")
		(7 "B.SilkS" user "Ref Des/Silkscreen Bottom")
		(1 "F.Mask" user "Board Geometry/Soldermask Top")
		(3 "B.Mask" user "Board Geometry/Soldermask Bottom")
		(17 "Dwgs.User" user "User.Drawings")
		(19 "Cmts.User" user "User.Comments")
		(21 "Eco1.User" user "User.Eco1")
		(23 "Eco2.User" user "User.Eco2")
		(25 "Edge.Cuts" user "Board Geometry/Outline")
		(27 "Margin" user)
		(31 "F.CrtYd" user "Package Geometry/Place Bound Top")
		(29 "B.CrtYd" user "Package Geometry/Place Bound Bottom")
		(35 "F.Fab" user "Ref Des/Assembly Top")
		(33 "B.Fab" user "Ref Des/Assembly Bottom")
	)
	(footprint ""
		(layer "B.Cu")
		(at 417.576 -6.5405)
		(property "Reference" "R3P50"
			(at 0 0 0)
			(layer "B.SilkS")
			(hide yes)
			(effects
				(font
					(size 1.27 1.27)
				)
				(justify mirror)
			)
		)
		(property "Value" ""
			(at 0 0 0)
			(layer "B.Fab")
			(effects
				(font
					(size 1.27 1.27)
				)
				(justify mirror)
			)
		)
		(duplicate_pad_numbers_are_jumpers no)
		(fp_rect
			(start -0.2794 0.9906)
			(end 0.2794 -0.1016)
			(stroke
				(width 0)
				(type default)
			)
			(fill no)
			(layer "B.CrtYd")
		)
		(fp_line
			(start -0.2794 -0.1016)
			(end 0.2794 -0.1016)
			(stroke
				(width 0.1)
				(type default)
			)
			(layer "B.Fab")
		)
		(fp_line
			(start -0.2794 0.9906)
			(end -0.2794 -0.1016)
			(stroke
				(width 0.1)
				(type default)
			)
			(layer "B.Fab")
		)
		(fp_line
			(start 0.2794 -0.1016)
			(end 0.2794 0.9906)
			(stroke
				(width 0.1)
				(type default)
			)
			(layer "B.Fab")
		)
		(fp_line
			(start 0.2794 0.9906)
			(end -0.2794 0.9906)
			(stroke
				(width 0.1)
				(type default)
			)
			(layer "B.Fab")
		)
		(pad "1" smd rect
			(at 0 0 180)
			(size 0.508 0.508)
			(layers "B.Cu" "B.Mask" "B.Paste")
			(net "P3V3_STBY")
		)
		(pad "2" smd rect
			(at 0 0.889 180)
			(size 0.508 0.508)
			(layers "B.Cu" "B.Mask" "B.Paste")
			(net "PWRGD_P3V3_STBY")
		)
		(zone
			(layer "B.Cu")
			(hatch none 0.5)
			(connect_pads
				(clearance 0)
			)
			(min_thickness 0.25)
			(keepout
				(tracks allowed)
				(vias not_allowed)
				(pads allowed)
				(copperpour not_allowed)
				(footprints allowed)
			)
			(placement
				(enabled no)
				(sheetname "")
			)
			(fill
				(thermal_gap 0.5)
				(thermal_bridge_width 0.5)
				(island_removal_mode 0)
			)
			(polygon
				(pts
					(xy 417.322 -5.9055) (xy 417.83 -5.9055) (xy 417.83 -6.2865) (xy 417.322 -6.2865)
				)
			)
		)
		(zone
			(layer "B.Cu")
			(hatch none 0.5)
			(connect_pads
				(clearance 0)
			)
			(min_thickness 0.25)
			(keepout
				(tracks not_allowed)
				(vias allowed)
				(pads allowed)
				(copperpour not_allowed)
				(footprints allowed)
			)
			(placement
				(enabled no)
				(sheetname "")
			)
			(fill
				(thermal_gap 0.5)
				(thermal_bridge_width 0.5)
				(island_removal_mode 0)
			)
			(polygon
				(pts
					(xy 417.322 -5.9055) (xy 417.83 -5.9055) (xy 417.83 -6.2865) (xy 417.322 -6.2865)
				)
			)
		)
	)
	(footprint ""
		(layer "B.Cu")
		(at 49.4284 -78.359)
		(property "Reference" "C9P10"
			(at 0 0 0)
			(layer "B.SilkS")
			(hide yes)
			(effects
				(font
					(size 1.27 1.27)
				)
				(justify mirror)
			)
		)
		(property "Value" ""
			(at 0 0 0)
			(layer "B.Fab")
			(effects
				(font
					(size 1.27 1.27)
				)
				(justify mirror)
			)
		)
		(duplicate_pad_numbers_are_jumpers no)
		(fp_poly
			(pts
				(xy 0.4953 -0.2032) (xy -0.4953 -0.2032) (xy -0.4953 1.6002) (xy 0.4953 1.6002)
			)
			(stroke
				(width 0)
				(type default)
			)
			(fill no)
			(layer "B.CrtYd")
		)
		(fp_line
			(start -0.4953 -0.2032)
			(end -0.4953 1.6002)
			(stroke
				(width 0.1)
				(type default)
			)
			(layer "B.Fab")
		)
		(fp_line
			(start -0.4953 1.6002)
			(end 0.4953 1.6002)
			(stroke
				(width 0.1)
				(type default)
			)
			(layer "B.Fab")
		)
		(fp_line
			(start 0.4953 -0.2032)
			(end -0.4953 -0.2032)
			(stroke
				(width 0.1)
				(type default)
			)
			(layer "B.Fab")
		)
		(fp_line
			(start 0.4953 1.6002)
			(end 0.4953 -0.2032)
			(stroke
				(width 0.1)
				(type default)
			)
			(layer "B.Fab")
		)
		(pad "1" smd rect
			(at 0 0 180)
			(size 0.762 0.889)
			(layers "B.Cu" "B.Mask" "B.Paste")
			(net "PVCCIN_CPU1")
		)
		(pad "2" smd rect
			(at 0 1.397 180)
			(size 0.762 0.889)
			(layers "B.Cu" "B.Mask" "B.Paste")
			(net "GND")
		)
		(zone
			(layer "B.Cu")
			(hatch none 0.5)
			(connect_pads
				(clearance 0)
			)
			(min_thickness 0.25)
			(keepout
				(tracks not_allowed)
				(vias allowed)
				(pads allowed)
				(copperpour not_allowed)
				(footprints allowed)
			)
			(placement
				(enabled no)
				(sheetname "")
			)
			(fill
				(thermal_gap 0.5)
				(thermal_bridge_width 0.5)
				(island_removal_mode 0)
			)
			(polygon
				(pts
					(xy 49.8094 -77.9145) (xy 49.0474 -77.9145) (xy 49.0474 -77.4065) (xy 49.8094 -77.4065)
				)
			)
		)
	)
	(footprint ""
		(layer "B.Cu")
		(at 19.05 -95.5294)
		(property "Reference" "R9N8"
			(at 0 0 0)
			(layer "B.SilkS")
			(hide yes)
			(effects
				(font
					(size 1.27 1.27)
				)
				(justify mirror)
			)
		)
		(property "Value" ""
			(at 0 0 0)
			(layer "B.Fab")
			(effects
				(font
					(size 1.27 1.27)
				)
				(justify mirror)
			)
		)
		(duplicate_pad_numbers_are_jumpers no)
		(fp_poly
			(pts
				(xy 0.2794 -0.1016) (xy -0.2794 -0.1016) (xy -0.2794 0.9906) (xy 0.2794 0.9906)
			)
			(stroke
				(width 0)
				(type default)
			)
			(fill no)
			(layer "B.CrtYd")
		)
		(fp_line
			(start -0.2794 -0.1016)
			(end 0.2794 -0.1016)
			(stroke
				(width 0.1)
				(type default)
			)
			(layer "B.Fab")
		)
		(fp_line
			(start -0.2794 0.9906)
			(end -0.2794 -0.1016)
			(stroke
				(width 0.1)
				(type default)
			)
			(layer "B.Fab")
		)
		(fp_line
			(start 0.2794 -0.1016)
			(end 0.2794 0.9906)
			(stroke
				(width 0.1)
				(type default)
			)
			(layer "B.Fab")
		)
		(fp_line
			(start 0.2794 0.9906)
			(end -0.2794 0.9906)
			(stroke
				(width 0.1)
				(type default)
			)
			(layer "B.Fab")
		)
		(pad "1" smd rect
			(at 0 0 180)
			(size 0.508 0.508)
			(layers "B.Cu" "B.Mask" "B.Paste")
			(net "VR_PVCCIN_CPU1_XADDR1")
		)
		(pad "2" smd rect
			(at 0 0.889 180)
			(size 0.508 0.508)
			(layers "B.Cu" "B.Mask" "B.Paste")
			(net "GND")
		)
		(zone
			(layer "B.Cu")
			(hatch none 0.5)
			(connect_pads
				(clearance 0)
			)
			(min_thickness 0.25)
			(keepout
				(tracks allowed)
				(vias not_allowed)
				(pads allowed)
				(copperpour not_allowed)
				(footprints allowed)
			)
			(placement
				(enabled no)
				(sheetname "")
			)
			(fill
				(thermal_gap 0.5)
				(thermal_bridge_width 0.5)
				(island_removal_mode 0)
			)
			(polygon
				(pts
					(xy 19.304 -95.2754) (xy 18.796 -95.2754) (xy 18.796 -94.8944) (xy 19.304 -94.8944)
				)
			)
		)
		(zone
			(layer "B.Cu")
			(hatch none 0.5)
			(connect_pads
				(clearance 0)
			)
			(min_thickness 0.25)
			(keepout
				(tracks not_allowed)
				(vias allowed)
				(pads allowed)
				(copperpour not_allowed)
				(footprints allowed)
			)
			(placement
				(enabled no)
				(sheetname "")
			)
			(fill
				(thermal_gap 0.5)
				(thermal_bridge_width 0.5)
				(island_removal_mode 0)
			)
			(polygon
				(pts
					(xy 19.304 -94.8944) (xy 18.796 -94.8944) (xy 18.796 -95.2754) (xy 19.304 -95.2754)
				)
			)
		)
	)
)
